(kicad_pcb
	(version 20260206)
	(generator "pcbnew")
	(generator_version "10.0")
	(general
		(thickness 1.6)
		(legacy_teardrops no)
	)
	(paper "A4")
	(title_block
		(title "Wiwynn_Tioga_Pass_MB.brd")
		(comment 1 "Tioga Pass / footprints 2185-2190 of 4770")
	)
	(layers
		(0 "F.Cu" signal "TOP")
		(4 "In1.Cu" signal "L2GND")
		(6 "In2.Cu" signal "L3")
		(8 "In3.Cu" signal "L4GND")
		(10 "In4.Cu" signal "L5")
		(12 "In5.Cu" signal "L6GND")
		(14 "In6.Cu" signal "L7VCC")
		(16 "In7.Cu" signal "L8VCC")
		(18 "In8.Cu" signal "L9GND")
		(20 "In9.Cu" signal "L10")
		(22 "In10.Cu" signal "L11GND")
		(24 "In11.Cu" signal "L12")
		(26 "In12.Cu" signal "L13GND")
		(2 "B.Cu" signal "BOTTOM")
		(9 "F.Adhes" user "F.Adhesive")
		(11 "B.Adhes" user "B.Adhesive")
		(13 "F.Paste" user "Package Geometry/Pastemask Top")
		(15 "B.Paste" user "Package Geometry/Pastemask Bottom")
		(5 "F.SilkS" user "Ref Des/Silkscreen Top")
		(7 "B.SilkS" user "Ref Des/Silkscreen Bottom")
		(1 "F.Mask" user "Board Geometry/Soldermask Top")
		(3 "B.Mask" user "Board Geometry/Soldermask Bottom")
		(17 "Dwgs.User" user "User.Drawings")
		(19 "Cmts.User" user "User.Comments")
		(21 "Eco1.User" user "User.Eco1")
		(23 "Eco2.User" user "User.Eco2")
		(25 "Edge.Cuts" user "Board Geometry/Outline")
		(27 "Margin" user)
		(31 "F.CrtYd" user "Package Geometry/Place Bound Top")
		(29 "B.CrtYd" user "Package Geometry/Place Bound Bottom")
		(35 "F.Fab" user "Ref Des/Assembly Top")
		(33 "B.Fab" user "Ref Des/Assembly Bottom")
	)
	(footprint ""
		(layer "F.Cu")
		(at 184.6072 -152.527 180)
		(property "Reference" "C4A2"
			(at 0 0 180)
			(layer "F.SilkS")
			(hide yes)
			(effects
				(font
					(size 1.27 1.27)
				)
			)
		)
		(property "Value" ""
			(at 0 0 180)
			(layer "F.Fab")
			(effects
				(font
					(size 1.27 1.27)
				)
			)
		)
		(duplicate_pad_numbers_are_jumpers no)
		(fp_rect
			(start -0.3048 0.9906)
			(end 0.3048 -0.1016)
			(stroke
				(width 0)
				(type default)
			)
			(fill no)
			(layer "F.CrtYd")
		)
		(fp_line
			(start 0.3048 0.9906)
			(end 0.3048 -0.1016)
			(stroke
				(width 0.1)
				(type default)
			)
			(layer "F.Fab")
		)
		(fp_line
			(start 0.3048 -0.1016)
			(end -0.3048 -0.1016)
			(stroke
				(width 0.1)
				(type default)
			)
			(layer "F.Fab")
		)
		(fp_line
			(start -0.3048 0.9906)
			(end 0.3048 0.9906)
			(stroke
				(width 0.1)
				(type default)
			)
			(layer "F.Fab")
		)
		(fp_line
			(start -0.3048 -0.1016)
			(end -0.3048 0.9906)
			(stroke
				(width 0.1)
				(type default)
			)
			(layer "F.Fab")
		)
		(pad "1" smd rect
			(at 0 0 180)
			(size 0.508 0.508)
			(layers "F.Cu" "F.Mask" "F.Paste")
			(net "FM_PVTT_DEF_EN_R")
		)
		(pad "2" smd rect
			(at 0 0.889 180)
			(size 0.508 0.508)
			(layers "F.Cu" "F.Mask" "F.Paste")
			(net "GND")
		)
		(zone
			(layer "F.Cu")
			(hatch none 0.5)
			(connect_pads
				(clearance 0)
			)
			(min_thickness 0.25)
			(keepout
				(tracks not_allowed)
				(vias allowed)
				(pads allowed)
				(copperpour not_allowed)
				(footprints allowed)
			)
			(placement
				(enabled no)
				(sheetname "")
			)
			(fill
				(thermal_gap 0.5)
				(thermal_bridge_width 0.5)
				(island_removal_mode 0)
			)
			(polygon
				(pts
					(xy 184.8612 -153.162) (xy 184.3532 -153.162) (xy 184.3532 -152.781) (xy 184.8612 -152.781)
				)
			)
		)
		(zone
			(layer "F.Cu")
			(hatch none 0.5)
			(connect_pads
				(clearance 0)
			)
			(min_thickness 0.25)
			(keepout
				(tracks allowed)
				(vias not_allowed)
				(pads allowed)
				(copperpour not_allowed)
				(footprints allowed)
			)
			(placement
				(enabled no)
				(sheetname "")
			)
			(fill
				(thermal_gap 0.5)
				(thermal_bridge_width 0.5)
				(island_removal_mode 0)
			)
			(polygon
				(pts
					(xy 184.8612 -153.162) (xy 184.3532 -153.162) (xy 184.3532 -152.781) (xy 184.8612 -152.781)
				)
			)
		)
	)
	(footprint ""
		(layer "F.Cu")
		(at 356.09784 -134.22757)
		(property "Reference" "C7B1"
			(at 0 0 0)
			(layer "F.SilkS")
			(hide yes)
			(effects
				(font
					(size 1.27 1.27)
				)
			)
		)
		(property "Value" ""
			(at 0 0 0)
			(layer "F.Fab")
			(effects
				(font
					(size 1.27 1.27)
				)
			)
		)
		(duplicate_pad_numbers_are_jumpers no)
		(fp_poly
			(pts
				(xy 0.3048 -0.1016) (xy 0.3048 0.9906) (xy -0.3048 0.9906) (xy -0.3048 -0.1016)
			)
			(stroke
				(width 0)
				(type default)
			)
			(fill no)
			(layer "F.CrtYd")
		)
		(fp_line
			(start -0.3048 -0.1016)
			(end -0.3048 0.9906)
			(stroke
				(width 0.1)
				(type default)
			)
			(layer "F.Fab")
		)
		(fp_line
			(start -0.3048 0.9906)
			(end 0.3048 0.9906)
			(stroke
				(width 0.1)
				(type default)
			)
			(layer "F.Fab")
		)
		(fp_line
			(start 0.3048 -0.1016)
			(end -0.3048 -0.1016)
			(stroke
				(width 0.1)
				(type default)
			)
			(layer "F.Fab")
		)
		(fp_line
			(start 0.3048 0.9906)
			(end 0.3048 -0.1016)
			(stroke
				(width 0.1)
				(type default)
			)
			(layer "F.Fab")
		)
		(pad "1" smd rect
			(at 0 0)
			(size 0.508 0.508)
			(layers "F.Cu" "F.Mask" "F.Paste")
			(net "VR_PVDDQ_DEF_VD12")
		)
		(pad "2" smd rect
			(at 0 0.889)
			(size 0.508 0.508)
			(layers "F.Cu" "F.Mask" "F.Paste")
			(net "GND")
		)
		(zone
			(layer "F.Cu")
			(hatch none 0.5)
			(connect_pads
				(clearance 0)
			)
			(min_thickness 0.25)
			(keepout
				(tracks allowed)
				(vias not_allowed)
				(pads allowed)
				(copperpour not_allowed)
				(footprints allowed)
			)
			(placement
				(enabled no)
				(sheetname "")
			)
			(fill
				(thermal_gap 0.5)
				(thermal_bridge_width 0.5)
				(island_removal_mode 0)
			)
			(polygon
				(pts
					(xy 355.84384 -133.97357) (xy 356.35184 -133.97357) (xy 356.35184 -133.59257) (xy 355.84384 -133.59257)
				)
			)
		)
		(zone
			(layer "F.Cu")
			(hatch none 0.5)
			(connect_pads
				(clearance 0)
			)
			(min_thickness 0.25)
			(keepout
				(tracks not_allowed)
				(vias allowed)
				(pads allowed)
				(copperpour not_allowed)
				(footprints allowed)
			)
			(placement
				(enabled no)
				(sheetname "")
			)
			(fill
				(thermal_gap 0.5)
				(thermal_bridge_width 0.5)
				(island_removal_mode 0)
			)
			(polygon
				(pts
					(xy 355.84384 -133.59257) (xy 356.35184 -133.59257) (xy 356.35184 -133.97357) (xy 355.84384 -133.97357)
				)
			)
		)
	)
	(footprint ""
		(layer "F.Cu")
		(at 389.9535 -79.8322 180)
		(property "Reference" "R7W4"
			(at -0.8382 -0.67818 180)
			(unlocked yes)
			(layer "F.SilkS")
			(effects
				(font
					(size 0.4064 0.254)
					(thickness 0.1524)
				)
				(justify left)
			)
		)
		(property "Value" ""
			(at 0 0 180)
			(layer "F.Fab")
			(effects
				(font
					(size 1.27 1.27)
				)
			)
		)
		(duplicate_pad_numbers_are_jumpers no)
		(fp_poly
			(pts
				(xy -0.2794 -0.1016) (xy 0.2794 -0.1016) (xy 0.2794 0.9906) (xy -0.2794 0.9906)
			)
			(stroke
				(width 0)
				(type default)
			)
			(fill no)
			(layer "F.CrtYd")
		)
		(fp_line
			(start 0.2794 0.9906)
			(end 0.2794 -0.1016)
			(stroke
				(width 0.1)
				(type default)
			)
			(layer "F.Fab")
		)
		(fp_line
			(start 0.2794 -0.1016)
			(end -0.2794 -0.1016)
			(stroke
				(width 0.1)
				(type default)
			)
			(layer "F.Fab")
		)
		(fp_line
			(start -0.2794 0.9906)
			(end 0.2794 0.9906)
			(stroke
				(width 0.1)
				(type default)
			)
			(layer "F.Fab")
		)
		(fp_line
			(start -0.2794 -0.1016)
			(end -0.2794 0.9906)
			(stroke
				(width 0.1)
				(type default)
			)
			(layer "F.Fab")
		)
		(pad "1" smd rect
			(at 0 0 180)
			(size 0.508 0.508)
			(layers "F.Cu" "F.Mask" "F.Paste")
			(net "PVCCIO_CPU0")
		)
		(pad "2" smd rect
			(at 0 0.889 180)
			(size 0.508 0.508)
			(layers "F.Cu" "F.Mask" "F.Paste")
			(net "P0V7_GTL2104_VREF_0")
		)
		(zone
			(layer "F.Cu")
			(hatch none 0.5)
			(connect_pads
				(clearance 0)
			)
			(min_thickness 0.25)
			(keepout
				(tracks not_allowed)
				(vias allowed)
				(pads allowed)
				(copperpour not_allowed)
				(footprints allowed)
			)
			(placement
				(enabled no)
				(sheetname "")
			)
			(fill
				(thermal_gap 0.5)
				(thermal_bridge_width 0.5)
				(island_removal_mode 0)
			)
			(polygon
				(pts
					(xy 390.2075 -80.4672) (xy 389.6995 -80.4672) (xy 389.6995 -80.0862) (xy 390.2075 -80.0862)
				)
			)
		)
		(zone
			(layer "F.Cu")
			(hatch none 0.5)
			(connect_pads
				(clearance 0)
			)
			(min_thickness 0.25)
			(keepout
				(tracks allowed)
				(vias not_allowed)
				(pads allowed)
				(copperpour not_allowed)
				(footprints allowed)
			)
			(placement
				(enabled no)
				(sheetname "")
			)
			(fill
				(thermal_gap 0.5)
				(thermal_bridge_width 0.5)
				(island_removal_mode 0)
			)
			(polygon
				(pts
					(xy 390.2075 -80.0862) (xy 389.6995 -80.0862) (xy 389.6995 -80.4672) (xy 390.2075 -80.4672)
				)
			)
		)
	)
	(footprint ""
		(layer "F.Cu")
		(at 347.622114 -22.5933 180)
		(property "Reference" "R7F19"
			(at 0 0 180)
			(layer "F.SilkS")
			(hide yes)
			(effects
				(font
					(size 1.27 1.27)
				)
			)
		)
		(property "Value" ""
			(at 0 0 180)
			(layer "F.Fab")
			(effects
				(font
					(size 1.27 1.27)
				)
			)
		)
		(duplicate_pad_numbers_are_jumpers no)
		(fp_rect
			(start 0.2794 -0.1016)
			(end -0.2794 0.9906)
			(stroke
				(width 0)
				(type default)
			)
			(fill no)
			(layer "F.CrtYd")
		)
		(fp_line
			(start 0.2794 0.9906)
			(end 0.2794 -0.1016)
			(stroke
				(width 0.1)
				(type default)
			)
			(layer "F.Fab")
		)
		(fp_line
			(start 0.2794 -0.1016)
			(end -0.2794 -0.1016)
			(stroke
				(width 0.1)
				(type default)
			)
			(layer "F.Fab")
		)
		(fp_line
			(start -0.2794 0.9906)
			(end 0.2794 0.9906)
			(stroke
				(width 0.1)
				(type default)
			)
			(layer "F.Fab")
		)
		(fp_line
			(start -0.2794 -0.1016)
			(end -0.2794 0.9906)
			(stroke
				(width 0.1)
				(type default)
			)
			(layer "F.Fab")
		)
		(pad "1" smd rect
			(at 0 0 180)
			(size 0.508 0.508)
			(layers "F.Cu" "F.Mask" "F.Paste")
			(net "P3V3_STBY")
		)
		(pad "2" smd rect
			(at 0 0.889 180)
			(size 0.508 0.508)
			(layers "F.Cu" "F.Mask" "F.Paste")
			(net "PWRGD_PVPP_ABC_R")
		)
		(zone
			(layer "F.Cu")
			(hatch none 0.5)
			(connect_pads
				(clearance 0)
			)
			(min_thickness 0.25)
			(keepout
				(tracks not_allowed)
				(vias allowed)
				(pads allowed)
				(copperpour not_allowed)
				(footprints allowed)
			)
			(placement
				(enabled no)
				(sheetname "")
			)
			(fill
				(thermal_gap 0.5)
				(thermal_bridge_width 0.5)
				(island_removal_mode 0)
			)
			(polygon
				(pts
					(xy 347.368114 -22.8473) (xy 347.876114 -22.8473) (xy 347.876114 -23.2283) (xy 347.368114 -23.2283)
				)
			)
		)
		(zone
			(layer "F.Cu")
			(hatch none 0.5)
			(connect_pads
				(clearance 0)
			)
			(min_thickness 0.25)
			(keepout
				(tracks allowed)
				(vias not_allowed)
				(pads allowed)
				(copperpour not_allowed)
				(footprints allowed)
			)
			(placement
				(enabled no)
				(sheetname "")
			)
			(fill
				(thermal_gap 0.5)
				(thermal_bridge_width 0.5)
				(island_removal_mode 0)
			)
			(polygon
				(pts
					(xy 347.368114 -22.8473) (xy 347.876114 -22.8473) (xy 347.876114 -23.2283) (xy 347.368114 -23.2283)
				)
			)
		)
	)
	(footprint ""
		(layer "F.Cu")
		(at 189.70498 -73.5457)
		(property "Reference" "R4D39"
			(at 0 0 0)
			(layer "F.SilkS")
			(hide yes)
			(effects
				(font
					(size 1.27 1.27)
				)
			)
		)
		(property "Value" ""
			(at 0 0 0)
			(layer "F.Fab")
			(effects
				(font
					(size 1.27 1.27)
				)
			)
		)
		(duplicate_pad_numbers_are_jumpers no)
		(fp_rect
			(start -0.2794 0.9906)
			(end 0.2794 -0.1016)
			(stroke
				(width 0)
				(type default)
			)
			(fill no)
			(layer "F.CrtYd")
		)
		(fp_line
			(start -0.2794 -0.1016)
			(end -0.2794 0.9906)
			(stroke
				(width 0.1)
				(type default)
			)
			(layer "F.Fab")
		)
		(fp_line
			(start -0.2794 0.9906)
			(end 0.2794 0.9906)
			(stroke
				(width 0.1)
				(type default)
			)
			(layer "F.Fab")
		)
		(fp_line
			(start 0.2794 -0.1016)
			(end -0.2794 -0.1016)
			(stroke
				(width 0.1)
				(type default)
			)
			(layer "F.Fab")
		)
		(fp_line
			(start 0.2794 0.9906)
			(end 0.2794 -0.1016)
			(stroke
				(width 0.1)
				(type default)
			)
			(layer "F.Fab")
		)
		(pad "1" smd rect
			(at 0 0)
			(size 0.508 0.508)
			(layers "F.Cu" "F.Mask" "F.Paste")
			(net "VSENSE_PVSA_CPU0_P")
		)
		(pad "2" smd rect
			(at 0 0.889)
			(size 0.508 0.508)
			(layers "F.Cu" "F.Mask" "F.Paste")
			(net "VSENSE_PVSA_CPU0_BVSP")
		)
		(zone
			(layer "F.Cu")
			(hatch none 0.5)
			(connect_pads
				(clearance 0)
			)
			(min_thickness 0.25)
			(keepout
				(tracks not_allowed)
				(vias allowed)
				(pads allowed)
				(copperpour not_allowed)
				(footprints allowed)
			)
			(placement
				(enabled no)
				(sheetname "")
			)
			(fill
				(thermal_gap 0.5)
				(thermal_bridge_width 0.5)
				(island_removal_mode 0)
			)
			(polygon
				(pts
					(xy 189.45098 -72.9107) (xy 189.95898 -72.9107) (xy 189.95898 -73.2917) (xy 189.45098 -73.2917)
				)
			)
		)
		(zone
			(layer "F.Cu")
			(hatch none 0.5)
			(connect_pads
				(clearance 0)
			)
			(min_thickness 0.25)
			(keepout
				(tracks allowed)
				(vias not_allowed)
				(pads allowed)
				(copperpour not_allowed)
				(footprints allowed)
			)
			(placement
				(enabled no)
				(sheetname "")
			)
			(fill
				(thermal_gap 0.5)
				(thermal_bridge_width 0.5)
				(island_removal_mode 0)
			)
			(polygon
				(pts
					(xy 189.45098 -72.9107) (xy 189.95898 -72.9107) (xy 189.95898 -73.2917) (xy 189.45098 -73.2917)
				)
			)
		)
	)
	(footprint ""
		(layer "F.Cu")
		(at 488.887516 -125.92685 180)
		(property "Reference" "Q9B1"
			(at 0 0 180)
			(layer "F.SilkS")
			(hide yes)
			(effects
				(font
					(size 1.27 1.27)
				)
			)
		)
		(property "Value" "*"
			(at -4.8514 -0.40005 180)
			(unlocked yes)
			(layer "F.Fab")
			(hide yes)
			(effects
				(font
					(size 0.889 0.889)
					(thickness 0.1524)
				)
			)
		)
		(property "Device Type" "2SB2907A-B0-00001-GP_DISCRET-GA"
			(at -4.8514 -1.92405 180)
			(unlocked yes)
			(layer "F.Fab")
			(hide yes)
			(effects
				(font
					(size 0.889 0.889)
					(thickness 0.1524)
				)
			)
		)
		(duplicate_pad_numbers_are_jumpers no)
		(fp_line
			(start 3.3274 0.8255)
			(end 2.59334 0.8255)
			(stroke
				(width 0.1524)
				(type default)
			)
			(layer "F.SilkS")
		)
		(fp_line
			(start 3.3274 -0.8255)
			(end 3.3274 0.8255)
			(stroke
				(width 0.1524)
				(type default)
			)
			(layer "F.SilkS")
		)
		(fp_line
			(start 2.460752 -0.8255)
			(end 3.3274 -0.8255)
			(stroke
				(width 0.1524)
				(type default)
			)
			(layer "F.SilkS")
		)
		(fp_line
			(start -2.188718 -1.3208)
			(end 2.188718 -1.3208)
			(stroke
				(width 0.1524)
				(type default)
			)
			(layer "F.SilkS")
		)
		(fp_line
			(start -2.59334 0.8255)
			(end -3.3274 0.8255)
			(stroke
				(width 0.1524)
				(type default)
			)
			(layer "F.SilkS")
		)
		(fp_line
			(start -3.3274 0.8255)
			(end -3.3274 -0.8255)
			(stroke
				(width 0.1524)
				(type default)
			)
			(layer "F.SilkS")
		)
		(fp_line
			(start -3.3274 -0.8255)
			(end -2.460752 -0.8255)
			(stroke
				(width 0.1524)
				(type default)
			)
			(layer "F.SilkS")
		)
		(fp_arc
			(start 2.59334 0.8255)
			(mid 0 2.870159)
			(end -2.59334 0.8255)
			(stroke
				(width 0.1524)
				(type default)
			)
			(layer "F.SilkS")
		)
		(fp_arc
			(start 2.188718 -1.3208)
			(mid 2.337892 -1.080376)
			(end 2.460752 -0.8255)
			(stroke
				(width 0.1524)
				(type default)
			)
			(layer "F.SilkS")
		)
		(fp_arc
			(start -2.460752 -0.8255)
			(mid -2.337885 -1.080372)
			(end -2.188718 -1.3208)
			(stroke
				(width 0.1524)
				(type default)
			)
			(layer "F.SilkS")
		)
		(fp_poly
			(pts
				(arc
					(start 2.413 0.2286)
					(mid 0 2.616334)
					(end -2.413 0.2286)
				)
				(xy -2.7432 0.2286) (xy -2.7432 -0.2286)
				(arc
					(start -2.374138 -0.2286)
					(mid -2.252325 -0.662833)
					(end -2.051812 -1.0668)
				)
				(arc
					(start 2.051812 -1.0668)
					(mid 2.252296 -0.662822)
					(end 2.374138 -0.2286)
				)
				(xy 2.7432 -0.2286) (xy 2.7432 0.2286)
			)
			(stroke
				(width 0)
				(type default)
			)
			(fill no)
			(layer "F.CrtYd")
		)
		(fp_poly
			(pts
				(arc
					(start 2.786634 1.0795)
					(mid 0 3.124369)
					(end -2.786634 1.0795)
				)
				(xy -3.5814 1.0795) (xy -3.5814 -1.0795)
				(arc
					(start -2.624328 -1.0795)
					(mid -2.483414 -1.33481)
					(end -2.31775 -1.5748)
				)
				(xy -0.000762 -1.5748) (xy -0.000762 -1.067054)
				(arc
					(start -2.052066 -1.067054)
					(mid -2.252571 -0.663082)
					(end -2.374392 -0.228854)
				)
				(xy -2.743454 -0.228854) (xy -2.743454 0.228854)
				(arc
					(start -2.413254 0.228854)
					(mid 0 2.61659)
					(end 2.413254 0.228854)
				)
				(xy 2.743454 0.228854) (xy 2.743454 -0.228854)
				(arc
					(start 2.374392 -0.228854)
					(mid 2.252549 -0.663073)
					(end 2.052066 -1.067054)
				)
				(xy 0.000762 -1.067054) (xy 0.000762 -1.5748)
				(arc
					(start 2.31775 -1.5748)
					(mid 2.483417 -1.334811)
					(end 2.624328 -1.0795)
				)
				(xy 3.5814 -1.0795) (xy 3.5814 1.0795)
			)
			(stroke
				(width 0)
				(type default)
			)
			(fill no)
			(layer "F.CrtYd")
		)
		(fp_poly
			(pts
				(arc
					(start 2.786634 1.0795)
					(mid 0 3.124369)
					(end -2.786634 1.0795)
				)
				(xy -3.5814 1.0795) (xy -3.5814 -1.0795)
				(arc
					(start -2.624328 -1.0795)
					(mid -2.483414 -1.33481)
					(end -2.31775 -1.5748)
				)
				(arc
					(start 2.31775 -1.5748)
					(mid 2.483417 -1.334811)
					(end 2.624328 -1.0795)
				)
				(xy 3.5814 -1.0795) (xy 3.5814 1.0795)
			)
			(stroke
				(width 0)
				(type default)
			)
			(fill no)
			(layer "F.Fab")
		)
		(pad "B" thru_hole circle
			(at 0 0 180)
			(size 1.143 1.143)
			(drill 0.7874)
			(layers "*.Cu" "*.Mask")
			(remove_unused_layers no)
			(net "ISENSE_TMP421_1_BC")
			(clearance 0.1778)
			(thermal_gap 0.1778)
		)
		(pad "C" thru_hole circle
			(at -2.500122 0 180)
			(size 1.143 1.143)
			(drill 0.7874)
			(layers "*.Cu" "*.Mask")
			(remove_unused_layers no)
			(net "ISENSE_TMP421_1_BC")
			(clearance 0.1778)
			(thermal_gap 0.1778)
		)
		(pad "E" thru_hole circle
			(at 2.500122 0 180)
			(size 1.143 1.143)
			(drill 0.7874)
			(layers "*.Cu" "*.Mask")
			(remove_unused_layers no)
			(net "ISENSE_TMP421_1_E")
			(clearance 0.1778)
			(thermal_gap 0.1778)
		)
	)
)
